(kicad_pcb
	(version 20241229)
	(generator "pcbnew")
	(generator_version "9.0")
	(general
		(thickness 1.6296)
		(legacy_teardrops no)
	)
	(paper "A3")
	(title_block
		(title "Thunderbolt to 10GbE adapter")
		(date "2026-04-21")
		(rev "1.1.0")
		(company "Antmicro Ltd")
		(comment 1 "www.antmicro.com")
		(comment 9 "footprints 369-373 of 703")
	)
	(layers
		(0 "F.Cu" signal)
		(4 "In1.Cu" signal)
		(6 "In2.Cu" signal)
		(8 "In3.Cu" signal)
		(10 "In4.Cu" signal)
		(12 "In5.Cu" signal)
		(14 "In6.Cu" signal)
		(2 "B.Cu" signal)
		(9 "F.Adhes" user "F.Adhesive")
		(11 "B.Adhes" user "B.Adhesive")
		(13 "F.Paste" user)
		(15 "B.Paste" user)
		(5 "F.SilkS" user "F.Silkscreen")
		(7 "B.SilkS" user "B.Silkscreen")
		(1 "F.Mask" user)
		(3 "B.Mask" user)
		(17 "Dwgs.User" user "User.Drawings")
		(19 "Cmts.User" user "User.Comments")
		(21 "Eco1.User" user "User.Eco1")
		(23 "Eco2.User" user "User.Eco2")
		(25 "Edge.Cuts" user)
		(27 "Margin" user)
		(31 "F.CrtYd" user "F.Courtyard")
		(29 "B.CrtYd" user "B.Courtyard")
		(35 "F.Fab" user)
		(33 "B.Fab" user)
	)
	(footprint "antmicro-footprints:R_0402_1005Metric"
		(layer "F.Cu")
		(at 145.8 128.2 -90)
		(descr "Resistor SMD 0402")
		(tags "resistor SMD 0402")
		(property "Reference" "R82"
			(at 3.2 -0.4 270)
			(layer "F.SilkS")
			(effects
				(font
					(size 0.7 0.7)
					(thickness 0.15)
				)
				(justify left bottom)
			)
		)
		(property "Value" "R_3k3_0402"
			(at -1.011843 1.772047 270)
			(layer "F.Fab")
			(effects
				(font
					(size 0.7 0.7)
					(thickness 0.15)
				)
				(justify left bottom)
			)
		)
		(property "Datasheet" "https://www.bourns.com/docs/product-datasheets/cr.pdf"
			(at 0 0 270)
			(layer "F.Fab")
			(hide yes)
			(effects
				(font
					(size 1.27 1.27)
					(thickness 0.15)
				)
			)
		)
		(property "Description" "SMD Chip Resistor, 3.3 kohm, ± 1%, 63 mW, 0402 [1005 Metric], Thick Film, General Purpose"
			(at 0 0 270)
			(layer "F.Fab")
			(hide yes)
			(effects
				(font
					(size 1.27 1.27)
					(thickness 0.15)
				)
			)
		)
		(property "MPN" "CR0402-FX-3301GLF"
			(at 0 0 270)
			(unlocked yes)
			(layer "F.Fab")
			(hide yes)
			(effects
				(font
					(size 1 1)
					(thickness 0.15)
				)
			)
		)
		(property "Manufacturer" "Bourns"
			(at 0 0 270)
			(unlocked yes)
			(layer "F.Fab")
			(hide yes)
			(effects
				(font
					(size 1 1)
					(thickness 0.15)
				)
			)
		)
		(property "License" "Apache-2.0"
			(at 0 0 270)
			(unlocked yes)
			(layer "F.Fab")
			(hide yes)
			(effects
				(font
					(size 1 1)
					(thickness 0.15)
				)
			)
		)
		(property "Val" "3k3"
			(at 0 0 270)
			(unlocked yes)
			(layer "F.Fab")
			(hide yes)
			(effects
				(font
					(size 1 1)
					(thickness 0.15)
				)
			)
		)
		(property "Tolerance" "1%"
			(at 0 0 270)
			(unlocked yes)
			(layer "F.Fab")
			(hide yes)
			(effects
				(font
					(size 1 1)
					(thickness 0.15)
				)
			)
		)
		(property "Author" "Antmicro"
			(at 0 0 270)
			(unlocked yes)
			(layer "F.Fab")
			(hide yes)
			(effects
				(font
					(size 1 1)
					(thickness 0.15)
				)
			)
		)
		(sheetname "/TB flash memory/")
		(sheetfile "flash-memory.kicad_sch")
		(attr smd)
		(fp_rect
			(start -0.925 -0.47)
			(end 0.925 0.47)
			(stroke
				(width 0.05)
				(type default)
			)
			(fill no)
			(layer "F.CrtYd")
		)
		(fp_rect
			(start -0.5 -0.25)
			(end 0.5 0.25)
			(stroke
				(width 0.15)
				(type solid)
			)
			(fill no)
			(layer "F.Fab")
		)
		(fp_text user "${REFERENCE}"
			(at -0.95 3.168 270)
			(layer "F.Fab")
			(effects
				(font
					(size 0.7 0.7)
					(thickness 0.15)
				)
				(justify left bottom)
			)
		)
		(fp_text user "License: Apache-2.0"
			(at -0.95 5.169 270)
			(layer "F.Fab")
			(effects
				(font
					(size 0.7 0.7)
					(thickness 0.15)
				)
				(justify left bottom)
			)
		)
		(fp_text user "Author: Antmicro"
			(at -0.95 4.169 270)
			(layer "F.Fab")
			(effects
				(font
					(size 0.7 0.7)
					(thickness 0.15)
				)
				(justify left bottom)
			)
		)
		(pad "1" smd roundrect
			(at -0.48 0 270)
			(size 0.59 0.64)
			(layers "F.Cu" "F.Mask" "F.Paste")
			(roundrect_rratio 0.25)
			(net 359 "/PD and TB DC-DC/TB_FLASH.~{CE}")
			(pintype "passive")
		)
		(pad "2" smd roundrect
			(at 0.48 0 270)
			(size 0.59 0.64)
			(layers "F.Cu" "F.Mask" "F.Paste")
			(roundrect_rratio 0.25)
			(net 57 "+3V3_TB")
			(pintype "passive")
		)
	)
	(footprint "antmicro-footprints:C_0402_1005Metric"
		(layer "F.Cu")
		(at 117.8 128 180)
		(descr "Capacitor SMD 0402")
		(tags "capacitor SMD 0402")
		(property "Reference" "C51"
			(at -0.8 -0.2 180)
			(layer "F.SilkS")
			(effects
				(font
					(size 0.7 0.7)
					(thickness 0.15)
				)
				(justify left bottom)
			)
		)
		(property "Value" "C_220n_0402"
			(at -1.022927 2.155213 180)
			(layer "F.Fab")
			(effects
				(font
					(size 0.7 0.7)
					(thickness 0.15)
				)
				(justify left bottom)
			)
		)
		(property "Datasheet" "https://www.yageo.com/en/Chart/Download/pdf/CC0402KRX5R6BB224"
			(at 0 0 180)
			(layer "F.Fab")
			(hide yes)
			(effects
				(font
					(size 1.27 1.27)
					(thickness 0.15)
				)
			)
		)
		(property "Description" "SMD Multilayer Ceramic Capacitor, 0.22 µF, 10 V, 0402 [1005 Metric], ± 10%, X5R, CC Series"
			(at 0 0 180)
			(layer "F.Fab")
			(hide yes)
			(effects
				(font
					(size 1.27 1.27)
					(thickness 0.15)
				)
			)
		)
		(property "MPN" "CC0402KRX5R6BB224"
			(at 0 0 180)
			(unlocked yes)
			(layer "F.Fab")
			(hide yes)
			(effects
				(font
					(size 1 1)
					(thickness 0.15)
				)
			)
		)
		(property "Manufacturer" "YAGEO"
			(at 0 0 180)
			(unlocked yes)
			(layer "F.Fab")
			(hide yes)
			(effects
				(font
					(size 1 1)
					(thickness 0.15)
				)
			)
		)
		(property "License" "Apache-2.0"
			(at 0 0 180)
			(unlocked yes)
			(layer "F.Fab")
			(hide yes)
			(effects
				(font
					(size 1 1)
					(thickness 0.15)
				)
			)
		)
		(property "Val" "220n"
			(at 0 0 180)
			(unlocked yes)
			(layer "F.Fab")
			(hide yes)
			(effects
				(font
					(size 1 1)
					(thickness 0.15)
				)
			)
		)
		(property "Voltage" ""
			(at 0 0 180)
			(unlocked yes)
			(layer "F.Fab")
			(hide yes)
			(effects
				(font
					(size 1 1)
					(thickness 0.15)
				)
			)
		)
		(property "Dielectric" ""
			(at 0 0 180)
			(unlocked yes)
			(layer "F.Fab")
			(hide yes)
			(effects
				(font
					(size 1 1)
					(thickness 0.15)
				)
			)
		)
		(property "Author" "Antmicro"
			(at 0 0 180)
			(unlocked yes)
			(layer "F.Fab")
			(hide yes)
			(effects
				(font
					(size 1 1)
					(thickness 0.15)
				)
			)
		)
		(sheetname "/TB Controller/")
		(sheetfile "tb.kicad_sch")
		(attr smd)
		(fp_rect
			(start -0.925 -0.47)
			(end 0.925 0.47)
			(stroke
				(width 0.05)
				(type default)
			)
			(fill no)
			(layer "F.CrtYd")
		)
		(fp_line
			(start 0.504 0.248)
			(end -0.494 0.248)
			(stroke
				(width 0.15)
				(type solid)
			)
			(layer "F.Fab")
		)
		(fp_line
			(start 0.504 -0.25)
			(end 0.504 0.248)
			(stroke
				(width 0.15)
				(type solid)
			)
			(layer "F.Fab")
		)
		(fp_line
			(start -0.494 0.248)
			(end -0.494 -0.25)
			(stroke
				(width 0.15)
				(type solid)
			)
			(layer "F.Fab")
		)
		(fp_line
			(start -0.494 -0.25)
			(end 0.504 -0.25)
			(stroke
				(width 0.15)
				(type solid)
			)
			(layer "F.Fab")
		)
		(fp_text user "Author: Antmicro"
			(at -0.939 3.399 180)
			(layer "F.Fab")
			(effects
				(font
					(size 0.7 0.7)
					(thickness 0.15)
				)
				(justify left bottom)
			)
		)
		(fp_text user "License: Apache-2.0"
			(at -0.939 5.799 180)
			(layer "F.Fab")
			(effects
				(font
					(size 0.7 0.7)
					(thickness 0.15)
				)
				(justify left bottom)
			)
		)
		(fp_text user "${REFERENCE}"
			(at -0.939 4.599 180)
			(layer "F.Fab")
			(effects
				(font
					(size 0.7 0.7)
					(thickness 0.15)
				)
				(justify left bottom)
			)
		)
		(pad "1" smd roundrect
			(at -0.48 0 180)
			(size 0.59 0.64)
			(layers "F.Cu" "F.Mask" "F.Paste")
			(roundrect_rratio 0.25)
			(net 320 "/TB Controller/TB_PCIE_TX3_N")
			(pintype "passive")
		)
		(pad "2" smd roundrect
			(at 0.48 0 180)
			(size 0.59 0.64)
			(layers "F.Cu" "F.Mask" "F.Paste")
			(roundrect_rratio 0.25)
			(net 328 "/TB Controller/PCIex4.RX3-")
			(pintype "passive")
		)
	)
	(footprint "antmicro-footprints:C_0603_1608Metric_EIA"
		(layer "F.Cu")
		(at 158.2 105.600001 90)
		(descr "Capacitor SMD 0603, IPC-7351 Density Level A")
		(tags "Capacitor 0603")
		(property "Reference" "C137"
			(at -17.849995 13.250002 90)
			(layer "F.SilkS")
			(effects
				(font
					(size 0.7 0.7)
					(thickness 0.15)
				)
			)
		)
		(property "Value" "C_22u_16V_0603"
			(at -1.42757 1.770288 90)
			(layer "F.Fab")
			(effects
				(font
					(size 0.7 0.7)
					(thickness 0.15)
				)
				(justify left bottom)
			)
		)
		(property "Datasheet" "https://product.samsungsem.com/mlcc/CL10A226MO7JZN.do"
			(at 0 0 90)
			(layer "F.Fab")
			(hide yes)
			(effects
				(font
					(size 1.27 1.27)
					(thickness 0.15)
				)
			)
		)
		(property "Description" "SMD Multilayer Ceramic Capacitor"
			(at 0 0 90)
			(layer "F.Fab")
			(hide yes)
			(effects
				(font
					(size 1.27 1.27)
					(thickness 0.15)
				)
			)
		)
		(property "MPN" "CL10A226MO7JZNC"
			(at 0 0 90)
			(unlocked yes)
			(layer "F.Fab")
			(hide yes)
			(effects
				(font
					(size 1 1)
					(thickness 0.15)
				)
			)
		)
		(property "Manufacturer" "Samsung Electro-Mechanics"
			(at 0 0 90)
			(unlocked yes)
			(layer "F.Fab")
			(hide yes)
			(effects
				(font
					(size 1 1)
					(thickness 0.15)
				)
			)
		)
		(property "License" "Apache-2.0"
			(at 0 0 90)
			(unlocked yes)
			(layer "F.Fab")
			(hide yes)
			(effects
				(font
					(size 1 1)
					(thickness 0.15)
				)
			)
		)
		(property "Author" "Antmicro"
			(at 0 0 90)
			(unlocked yes)
			(layer "F.Fab")
			(hide yes)
			(effects
				(font
					(size 1 1)
					(thickness 0.15)
				)
			)
		)
		(property "Val" "22u"
			(at 0 0 90)
			(unlocked yes)
			(layer "F.Fab")
			(hide yes)
			(effects
				(font
					(size 1 1)
					(thickness 0.15)
				)
			)
		)
		(property "Voltage" "16V"
			(at 0 0 90)
			(unlocked yes)
			(layer "F.Fab")
			(hide yes)
			(effects
				(font
					(size 1 1)
					(thickness 0.15)
				)
			)
		)
		(property "Dielectric" ""
			(at 0 0 90)
			(unlocked yes)
			(layer "F.Fab")
			(hide yes)
			(effects
				(font
					(size 1 1)
					(thickness 0.15)
				)
			)
		)
		(sheetname "/X710 DCDC converters/")
		(sheetfile "DCDC_converters_X710.kicad_sch")
		(attr smd)
		(fp_line
			(start -0.15 -0.55)
			(end 0.15 -0.55)
			(stroke
				(width 0.15)
				(type solid)
			)
			(layer "F.SilkS")
		)
		(fp_line
			(start -0.15 0.55)
			(end 0.15 0.55)
			(stroke
				(width 0.15)
				(type solid)
			)
			(layer "F.SilkS")
		)
		(fp_rect
			(start -1.25 -0.65)
			(end 1.25 0.65)
			(stroke
				(width 0.05)
				(type solid)
			)
			(fill no)
			(layer "F.CrtYd")
		)
		(fp_rect
			(start -0.8 -0.45)
			(end 0.8 0.45)
			(stroke
				(width 0.15)
				(type solid)
			)
			(fill no)
			(layer "F.Fab")
		)
		(fp_text user "Author: Antmicro"
			(at -1.682 4.894 90)
			(layer "F.Fab")
			(effects
				(font
					(size 0.7 0.7)
					(thickness 0.15)
				)
				(justify left bottom)
			)
		)
		(fp_text user "${REFERENCE}"
			(at -1.682 3.895 90)
			(layer "F.Fab")
			(effects
				(font
					(size 0.7 0.7)
					(thickness 0.15)
				)
				(justify left bottom)
			)
		)
		(fp_text user "License: Apache-2.0"
			(at -1.682 5.895 90)
			(layer "F.Fab")
			(effects
				(font
					(size 0.7 0.7)
					(thickness 0.15)
				)
				(justify left bottom)
			)
		)
		(pad "1" smd roundrect
			(at -0.7 0 90)
			(size 0.8 1.1)
			(layers "F.Cu" "F.Mask" "F.Paste")
			(roundrect_rratio 0.2)
			(net 23 "GND")
			(pintype "passive")
		)
		(pad "2" smd roundrect
			(at 0.7 0 90)
			(size 0.8 1.1)
			(layers "F.Cu" "F.Mask" "F.Paste")
			(roundrect_rratio 0.2)
			(net 339 "/X710 DCDC converters/+1V0_OUT")
			(pintype "passive")
		)
	)
	(footprint "antmicro-footprints:C_0603_1608Metric"
		(layer "F.Cu")
		(at 151.654999 68.574999 -90)
		(descr "Capacitor SMD 0603")
		(tags "capacitor 0603")
		(property "Reference" "C226"
			(at -12.274999 -20.045 270)
			(layer "F.SilkS")
			(effects
				(font
					(size 0.7 0.7)
					(thickness 0.15)
				)
			)
		)
		(property "Value" "C_10u_10V_X7R_0603"
			(at -1.42757 1.770288 270)
			(layer "F.Fab")
			(effects
				(font
					(size 0.7 0.7)
					(thickness 0.15)
				)
				(justify left bottom)
			)
		)
		(property "Datasheet" "https://www.murata.com/products/productdetail?partno=GRM188Z71A106KA73%23"
			(at 0 0 270)
			(layer "F.Fab")
			(hide yes)
			(effects
				(font
					(size 1.27 1.27)
					(thickness 0.15)
				)
			)
		)
		(property "Description" "SMD Multilayer Ceramic Capacitor,  10µF, 10V, 0603, ±10%, X7R"
			(at 0 0 270)
			(layer "F.Fab")
			(hide yes)
			(effects
				(font
					(size 1.27 1.27)
					(thickness 0.15)
				)
			)
		)
		(property "MPN" "GRM188Z71A106KA73D"
			(at 0 0 270)
			(unlocked yes)
			(layer "F.Fab")
			(hide yes)
			(effects
				(font
					(size 1 1)
					(thickness 0.15)
				)
			)
		)
		(property "Val" "10u"
			(at 0 0 270)
			(unlocked yes)
			(layer "F.Fab")
			(hide yes)
			(effects
				(font
					(size 1 1)
					(thickness 0.15)
				)
			)
		)
		(property "Voltage" "10V"
			(at 0 0 270)
			(unlocked yes)
			(layer "F.Fab")
			(hide yes)
			(effects
				(font
					(size 1 1)
					(thickness 0.15)
				)
			)
		)
		(property "Dielectric" "X7R"
			(at 0 0 270)
			(unlocked yes)
			(layer "F.Fab")
			(hide yes)
			(effects
				(font
					(size 1 1)
					(thickness 0.15)
				)
			)
		)
		(property "Manufacturer" "Murata"
			(at 0 0 270)
			(unlocked yes)
			(layer "F.Fab")
			(hide yes)
			(effects
				(font
					(size 1 1)
					(thickness 0.15)
				)
			)
		)
		(property "License" "Apache-2.0"
			(at 0 0 270)
			(unlocked yes)
			(layer "F.Fab")
			(hide yes)
			(effects
				(font
					(size 1 1)
					(thickness 0.15)
				)
			)
		)
		(property "Author" "Antmicro"
			(at 0 0 270)
			(unlocked yes)
			(layer "F.Fab")
			(hide yes)
			(effects
				(font
					(size 1 1)
					(thickness 0.15)
				)
			)
		)
		(sheetname "/X710-AT2 power/")
		(sheetfile "x710-at2-power.kicad_sch")
		(attr smd)
		(fp_line
			(start -0.15 0.4)
			(end 0.15 0.4)
			(stroke
				(width 0.15)
				(type solid)
			)
			(layer "F.SilkS")
		)
		(fp_line
			(start -0.15 -0.4)
			(end 0.15 -0.4)
			(stroke
				(width 0.15)
				(type solid)
			)
			(layer "F.SilkS")
		)
		(fp_rect
			(start -1.25 -0.65)
			(end 1.25 0.65)
			(stroke
				(width 0.05)
				(type solid)
			)
			(fill no)
			(layer "F.CrtYd")
		)
		(fp_rect
			(start -0.8 -0.4)
			(end 0.8 0.4)
			(stroke
				(width 0.15)
				(type solid)
			)
			(fill no)
			(layer "F.Fab")
		)
		(fp_text user "${REFERENCE}"
			(at -1.682 3.895 270)
			(layer "F.Fab")
			(effects
				(font
					(size 0.7 0.7)
					(thickness 0.15)
				)
				(justify left bottom)
			)
		)
		(fp_text user "Author: Antmicro"
			(at -1.682 4.894 270)
			(layer "F.Fab")
			(effects
				(font
					(size 0.7 0.7)
					(thickness 0.15)
				)
				(justify left bottom)
			)
		)
		(fp_text user "License: Apache-2.0"
			(at -1.682 5.895 270)
			(layer "F.Fab")
			(effects
				(font
					(size 0.7 0.7)
					(thickness 0.15)
				)
				(justify left bottom)
			)
		)
		(pad "1" smd roundrect
			(at -0.7 0 270)
			(size 0.8 1)
			(layers "F.Cu" "F.Mask" "F.Paste")
			(roundrect_rratio 0.2)
			(net 23 "GND")
			(pintype "passive")
		)
		(pad "2" smd roundrect
			(at 0.7 0 270)
			(size 0.8 1)
			(layers "F.Cu" "F.Mask" "F.Paste")
			(roundrect_rratio 0.2)
			(net 7 "+3V3")
			(pintype "passive")
		)
	)
	(footprint "antmicro-footprints:TP_SMD_0.75mm"
		(layer "F.Cu")
		(at 142.9 122.25 180)
		(property "Reference" "TP4"
			(at 0 0.85 180)
			(layer "F.SilkS")
			(effects
				(font
					(size 0.7 0.7)
					(thickness 0.15)
				)
				(justify left bottom)
			)
		)
		(property "Value" "TP_0.75mm_SMD"
			(at 0 1.2 180)
			(layer "F.Fab")
			(effects
				(font
					(size 0.7 0.7)
					(thickness 0.15)
				)
				(justify left bottom)
			)
		)
		(property "Description" "SMT test point"
			(at 0 0 180)
			(layer "F.Fab")
			(hide yes)
			(effects
				(font
					(size 1.27 1.27)
					(thickness 0.15)
				)
			)
		)
		(property "License" "Apache-2.0"
			(at 0 0 180)
			(unlocked yes)
			(layer "F.Fab")
			(hide yes)
			(effects
				(font
					(size 1 1)
					(thickness 0.15)
				)
			)
		)
		(property "Manufacturer" ""
			(at 0 0 180)
			(unlocked yes)
			(layer "F.Fab")
			(hide yes)
			(effects
				(font
					(size 1 1)
					(thickness 0.15)
				)
			)
		)
		(property "MPN" ""
			(at 0 0 180)
			(unlocked yes)
			(layer "F.Fab")
			(hide yes)
			(effects
				(font
					(size 1 1)
					(thickness 0.15)
				)
			)
		)
		(property "Author" "Antmicro"
			(at 0 0 180)
			(unlocked yes)
			(layer "F.Fab")
			(hide yes)
			(effects
				(font
					(size 1 1)
					(thickness 0.15)
				)
			)
		)
		(sheetname "/TB Controller - Power/")
		(sheetfile "tb-power.kicad_sch")
		(attr exclude_from_pos_files exclude_from_bom)
		(fp_circle
			(center 0 0)
			(end 0.475 0)
			(stroke
				(width 0.05)
				(type default)
			)
			(fill no)
			(layer "F.CrtYd")
		)
		(fp_text user "${REFERENCE}"
			(at -0.4 2.7 180)
			(layer "F.Fab")
			(effects
				(font
					(size 0.7 0.7)
					(thickness 0.15)
				)
				(justify left bottom)
			)
		)
		(fp_text user "License: Apache-2.0"
			(at -0.4 5.101 180)
			(layer "F.Fab")
			(effects
				(font
					(size 0.7 0.7)
					(thickness 0.15)
				)
				(justify left bottom)
			)
		)
		(fp_text user "Author: Antmicro"
			(at -0.4 3.901 180)
			(layer "F.Fab")
			(effects
				(font
					(size 0.7 0.7)
					(thickness 0.15)
				)
				(justify left bottom)
			)
		)
		(pad "1" smd circle
			(at 0 0 180)
			(size 0.75 0.75)
			(layers "F.Cu" "F.Mask")
			(net 68 "/TB Controller - Power/VCC_0P9")
			(pinfunction "1")
			(pintype "passive")
		)
	)
)
